(kicad_pcb
	(version 20260206)
	(generator "pcbnew")
	(generator_version "10.0")
	(general
		(thickness 1.6)
		(legacy_teardrops no)
	)
	(paper "A4")
	(title_block
		(title "dpb — 14545-sa.0730WZS0815.brd")
		(comment 1 "Honey Badger (Wiwynn) / footprints 302-306 of 1066")
	)
	(layers
		(0 "F.Cu" signal "TOP")
		(4 "In1.Cu" signal "L2GND")
		(6 "In2.Cu" signal "L3")
		(8 "In3.Cu" signal "L4VCC")
		(10 "In4.Cu" signal "L5VCC")
		(12 "In5.Cu" signal "L6")
		(14 "In6.Cu" signal "L7GND")
		(2 "B.Cu" signal "BOTTOM")
		(9 "F.Adhes" user "F.Adhesive")
		(11 "B.Adhes" user "B.Adhesive")
		(13 "F.Paste" user "Package Geometry/Pastemask Top")
		(15 "B.Paste" user "Package Geometry/Pastemask Bottom")
		(5 "F.SilkS" user "Ref Des/Silkscreen Top")
		(7 "B.SilkS" user "Ref Des/Silkscreen Bottom")
		(1 "F.Mask" user "Board Geometry/Soldermask Top")
		(3 "B.Mask" user "Board Geometry/Soldermask Bottom")
		(17 "Dwgs.User" user "User.Drawings")
		(19 "Cmts.User" user "User.Comments")
		(21 "Eco1.User" user "User.Eco1")
		(23 "Eco2.User" user "User.Eco2")
		(25 "Edge.Cuts" user "Board Geometry/Outline")
		(27 "Margin" user)
		(31 "F.CrtYd" user "Package Geometry/Place Bound Top")
		(29 "B.CrtYd" user "Package Geometry/Place Bound Bottom")
		(35 "F.Fab" user "Ref Des/Assembly Top")
		(33 "B.Fab" user "Ref Des/Assembly Bottom")
	)
	(footprint ""
		(layer "F.Cu")
		(at 48.208946 -144.3736 90)
		(property "Reference" "Q42"
			(at 0 0 90)
			(layer "F.SilkS")
			(hide yes)
			(effects
				(font
					(size 1.27 1.27)
				)
			)
		)
		(property "Value" "PMBS3904-1-GP"
			(at 0 -9.0932 90)
			(unlocked yes)
			(layer "F.Fab")
			(hide yes)
			(effects
				(font
					(size 1.016 1.016)
					(thickness 0.1524)
				)
			)
		)
		(property "Device Type" "SOT-23-10H44"
			(at 0 -10.6172 90)
			(unlocked yes)
			(layer "F.Fab")
			(hide yes)
			(effects
				(font
					(size 1.016 1.016)
					(thickness 0.1524)
				)
			)
		)
		(duplicate_pad_numbers_are_jumpers no)
		(fp_line
			(start 1.651 -1.778)
			(end -1.651 -1.778)
			(stroke
				(width 0.1524)
				(type default)
			)
			(layer "F.SilkS")
		)
		(fp_line
			(start -1.651 -1.778)
			(end -1.651 1.778)
			(stroke
				(width 0.1524)
				(type default)
			)
			(layer "F.SilkS")
		)
		(fp_line
			(start 1.651 1.778)
			(end 1.651 -1.778)
			(stroke
				(width 0.1524)
				(type default)
			)
			(layer "F.SilkS")
		)
		(fp_line
			(start -1.651 1.778)
			(end 1.651 1.778)
			(stroke
				(width 0.1524)
				(type default)
			)
			(layer "F.SilkS")
		)
		(fp_line
			(start -0.9906 1.86309)
			(end -0.701294 2.15265)
			(stroke
				(width 0.0127)
				(type default)
			)
			(layer "F.SilkS")
		)
		(fp_line
			(start -0.994156 1.8669)
			(end -0.987044 1.8669)
			(stroke
				(width 0.0127)
				(type default)
			)
			(layer "F.SilkS")
		)
		(fp_line
			(start -1.003808 1.876552)
			(end -0.977646 1.876552)
			(stroke
				(width 0.0127)
				(type default)
			)
			(layer "F.SilkS")
		)
		(fp_line
			(start -0.635 1.8796)
			(end -1.7526 1.8796)
			(stroke
				(width 0.3302)
				(type default)
			)
			(layer "F.SilkS")
		)
		(fp_line
			(start -1.7526 1.8796)
			(end -1.7526 0.9906)
			(stroke
				(width 0.3302)
				(type default)
			)
			(layer "F.SilkS")
		)
		(fp_line
			(start -1.013206 1.88595)
			(end -0.967994 1.88595)
			(stroke
				(width 0.0127)
				(type default)
			)
			(layer "F.SilkS")
		)
		(fp_line
			(start -1.022858 1.895602)
			(end -0.958596 1.895602)
			(stroke
				(width 0.0127)
				(type default)
			)
			(layer "F.SilkS")
		)
		(fp_line
			(start -1.032256 1.905)
			(end -0.948944 1.905)
			(stroke
				(width 0.0127)
				(type default)
			)
			(layer "F.SilkS")
		)
		(fp_line
			(start -1.041908 1.914652)
			(end -0.939546 1.914652)
			(stroke
				(width 0.0127)
				(type default)
			)
			(layer "F.SilkS")
		)
		(fp_line
			(start -1.051306 1.92405)
			(end -0.929894 1.92405)
			(stroke
				(width 0.0127)
				(type default)
			)
			(layer "F.SilkS")
		)
		(fp_line
			(start -1.060958 1.933702)
			(end -0.920496 1.933702)
			(stroke
				(width 0.0127)
				(type default)
			)
			(layer "F.SilkS")
		)
		(fp_line
			(start -1.070356 1.9431)
			(end -0.910844 1.9431)
			(stroke
				(width 0.0127)
				(type default)
			)
			(layer "F.SilkS")
		)
		(fp_line
			(start -1.080008 1.952752)
			(end -0.901446 1.952752)
			(stroke
				(width 0.0127)
				(type default)
			)
			(layer "F.SilkS")
		)
		(fp_line
			(start -1.089406 1.96215)
			(end -0.891794 1.96215)
			(stroke
				(width 0.0127)
				(type default)
			)
			(layer "F.SilkS")
		)
		(fp_line
			(start -1.099058 1.971802)
			(end -0.882396 1.971802)
			(stroke
				(width 0.0127)
				(type default)
			)
			(layer "F.SilkS")
		)
		(fp_line
			(start -1.108456 1.9812)
			(end -0.872744 1.9812)
			(stroke
				(width 0.0127)
				(type default)
			)
			(layer "F.SilkS")
		)
		(fp_line
			(start -1.118108 1.990852)
			(end -0.863346 1.990852)
			(stroke
				(width 0.0127)
				(type default)
			)
			(layer "F.SilkS")
		)
		(fp_line
			(start -1.127506 2.00025)
			(end -0.853694 2.00025)
			(stroke
				(width 0.0127)
				(type default)
			)
			(layer "F.SilkS")
		)
		(fp_line
			(start -1.137158 2.009902)
			(end -0.844296 2.009902)
			(stroke
				(width 0.0127)
				(type default)
			)
			(layer "F.SilkS")
		)
		(fp_line
			(start -1.146556 2.0193)
			(end -0.834644 2.0193)
			(stroke
				(width 0.0127)
				(type default)
			)
			(layer "F.SilkS")
		)
		(fp_line
			(start -1.156208 2.028952)
			(end -0.825246 2.028952)
			(stroke
				(width 0.0127)
				(type default)
			)
			(layer "F.SilkS")
		)
		(fp_line
			(start -1.165606 2.03835)
			(end -0.815594 2.03835)
			(stroke
				(width 0.0127)
				(type default)
			)
			(layer "F.SilkS")
		)
		(fp_line
			(start -1.175258 2.048002)
			(end -0.806196 2.048002)
			(stroke
				(width 0.0127)
				(type default)
			)
			(layer "F.SilkS")
		)
		(fp_line
			(start -1.184656 2.0574)
			(end -0.796544 2.0574)
			(stroke
				(width 0.0127)
				(type default)
			)
			(layer "F.SilkS")
		)
		(fp_line
			(start -1.194308 2.067052)
			(end -0.787146 2.067052)
			(stroke
				(width 0.0127)
				(type default)
			)
			(layer "F.SilkS")
		)
		(fp_line
			(start -1.203706 2.07645)
			(end -0.777494 2.07645)
			(stroke
				(width 0.0127)
				(type default)
			)
			(layer "F.SilkS")
		)
		(fp_line
			(start -1.213358 2.086102)
			(end -0.768096 2.086102)
			(stroke
				(width 0.0127)
				(type default)
			)
			(layer "F.SilkS")
		)
		(fp_line
			(start -1.222756 2.0955)
			(end -0.758444 2.0955)
			(stroke
				(width 0.0127)
				(type default)
			)
			(layer "F.SilkS")
		)
		(fp_line
			(start -1.232408 2.105152)
			(end -0.749046 2.105152)
			(stroke
				(width 0.0127)
				(type default)
			)
			(layer "F.SilkS")
		)
		(fp_line
			(start -1.241806 2.11455)
			(end -0.739394 2.11455)
			(stroke
				(width 0.0127)
				(type default)
			)
			(layer "F.SilkS")
		)
		(fp_line
			(start -1.251458 2.124202)
			(end -0.729996 2.124202)
			(stroke
				(width 0.0127)
				(type default)
			)
			(layer "F.SilkS")
		)
		(fp_line
			(start -1.260856 2.1336)
			(end -0.720344 2.1336)
			(stroke
				(width 0.0127)
				(type default)
			)
			(layer "F.SilkS")
		)
		(fp_line
			(start -0.719074 2.145538)
			(end -1.265936 2.14122)
			(stroke
				(width 0.0127)
				(type default)
			)
			(layer "F.SilkS")
		)
		(fp_line
			(start -1.279398 2.152142)
			(end -0.9906 1.86309)
			(stroke
				(width 0.0127)
				(type default)
			)
			(layer "F.SilkS")
		)
		(fp_line
			(start -0.71628 2.15265)
			(end -1.26492 2.15265)
			(stroke
				(width 0.0127)
				(type default)
			)
			(layer "F.SilkS")
		)
		(fp_line
			(start -1.279144 2.15265)
			(end -0.701294 2.15265)
			(stroke
				(width 0.0127)
				(type default)
			)
			(layer "F.SilkS")
		)
		(fp_poly
			(pts
				(xy -1.285748 2.159) (xy -1.285748 1.8796) (xy -1.778 1.8796) (xy -1.778 -1.8796) (xy 1.778 -1.8796)
				(xy 1.778 1.8796) (xy -0.694944 1.8796) (xy -0.694944 2.159)
			)
			(stroke
				(width 0)
				(type default)
			)
			(fill no)
			(layer "F.CrtYd")
		)
		(fp_poly
			(pts
				(xy -1.285748 2.159) (xy -1.285748 1.8796) (xy -1.778 1.8796) (xy -1.778 -1.8796) (xy 1.778 -1.8796)
				(xy 1.778 1.8796) (xy -0.694944 1.8796) (xy -0.694944 2.159)
			)
			(stroke
				(width 0)
				(type default)
			)
			(fill no)
			(layer "F.Fab")
		)
		(pad "1" smd rect
			(at -0.98425 0.9525 90)
			(size 0.762 1.143)
			(layers "F.Cu" "F.Mask" "F.Paste")
			(net "FLT_HDD8_B")
		)
		(pad "2" smd rect
			(at 0.98425 0.9525 90)
			(size 0.762 1.143)
			(layers "F.Cu" "F.Mask" "F.Paste")
			(net "GND")
		)
		(pad "3" smd rect
			(at 0 -0.9525 90)
			(size 0.762 1.143)
			(layers "F.Cu" "F.Mask" "F.Paste")
			(net "DRIVE_ACT_8")
		)
	)
	(footprint ""
		(layer "F.Cu")
		(at 46.100746 -25.1587 90)
		(property "Reference" "PC21"
			(at 0 0 90)
			(layer "F.SilkS")
			(hide yes)
			(effects
				(font
					(size 1.27 1.27)
				)
			)
		)
		(property "Value" "SCD1U25V2KX-GP"
			(at 1.1811 -2.7051 90)
			(unlocked yes)
			(layer "F.Fab")
			(hide yes)
			(effects
				(font
					(size 1.016 1.016)
					(thickness 0.1524)
				)
			)
		)
		(property "Device Type" "C402H22"
			(at 1.1811 -4.2291 90)
			(unlocked yes)
			(layer "F.Fab")
			(hide yes)
			(effects
				(font
					(size 1.016 1.016)
					(thickness 0.1524)
				)
			)
		)
		(duplicate_pad_numbers_are_jumpers no)
		(fp_rect
			(start -0.4318 0.9525)
			(end 0.4318 -0.9525)
			(stroke
				(width 0)
				(type default)
			)
			(fill no)
			(layer "F.CrtYd")
		)
		(fp_rect
			(start -0.4318 0.9525)
			(end 0.4318 -0.9525)
			(stroke
				(width 0)
				(type default)
			)
			(fill no)
			(layer "F.Fab")
		)
		(pad "1" smd custom
			(at 0 -0.4445 90)
			(size 0.1524 0.1524)
			(layers "F.Cu" "F.Mask" "F.Paste")
			(net "P5VB")
			(options
				(clearance outline)
				(anchor circle)
			)
			(primitives
				(gr_poly
					(pts
						(arc
							(start 0.3048 -0.2032)
							(mid 0.275042 -0.275042)
							(end 0.2032 -0.3048)
						)
						(arc
							(start -0.2032 -0.3048)
							(mid -0.275042 -0.275042)
							(end -0.3048 -0.2032)
						)
						(arc
							(start -0.3048 0.2032)
							(mid -0.275042 0.275042)
							(end -0.2032 0.3048)
						)
						(arc
							(start 0.2032 0.3048)
							(mid 0.275042 0.275042)
							(end 0.3048 0.2032)
						)
					)
					(width 0)
					(fill yes)
				)
			)
		)
		(pad "2" smd custom
			(at 0 0.4445 90)
			(size 0.1524 0.1524)
			(layers "F.Cu" "F.Mask" "F.Paste")
			(net "P5VB_LL_NET")
			(options
				(clearance outline)
				(anchor circle)
			)
			(primitives
				(gr_poly
					(pts
						(arc
							(start 0.3048 -0.2032)
							(mid 0.275042 -0.275042)
							(end 0.2032 -0.3048)
						)
						(arc
							(start -0.2032 -0.3048)
							(mid -0.275042 -0.275042)
							(end -0.3048 -0.2032)
						)
						(arc
							(start -0.3048 0.2032)
							(mid -0.275042 0.275042)
							(end -0.2032 0.3048)
						)
						(arc
							(start 0.2032 0.3048)
							(mid 0.275042 0.275042)
							(end 0.3048 0.2032)
						)
					)
					(width 0)
					(fill yes)
				)
			)
		)
	)
	(footprint ""
		(layer "F.Cu")
		(at 60.9854 -478.5868 180)
		(property "Reference" "Q57"
			(at 0 0 180)
			(layer "F.SilkS")
			(hide yes)
			(effects
				(font
					(size 1.27 1.27)
				)
			)
		)
		(property "Value" "2N7002-11-GP"
			(at 0.127 -8.9662 180)
			(unlocked yes)
			(layer "F.Fab")
			(hide yes)
			(effects
				(font
					(size 1.016 1.016)
					(thickness 0.1524)
				)
			)
		)
		(property "Device Type" "SOT23DGS2D4H44"
			(at 0.127 -10.4902 180)
			(unlocked yes)
			(layer "F.Fab")
			(hide yes)
			(effects
				(font
					(size 1.016 1.016)
					(thickness 0.1524)
				)
			)
		)
		(duplicate_pad_numbers_are_jumpers no)
		(fp_line
			(start 1.651 1.778)
			(end 1.651 -1.778)
			(stroke
				(width 0.1524)
				(type default)
			)
			(layer "F.SilkS")
		)
		(fp_line
			(start 1.651 -1.778)
			(end -1.651 -1.778)
			(stroke
				(width 0.1524)
				(type default)
			)
			(layer "F.SilkS")
		)
		(fp_line
			(start -1.651 1.778)
			(end 1.651 1.778)
			(stroke
				(width 0.1524)
				(type default)
			)
			(layer "F.SilkS")
		)
		(fp_line
			(start -1.651 -1.778)
			(end -1.651 1.778)
			(stroke
				(width 0.1524)
				(type default)
			)
			(layer "F.SilkS")
		)
		(fp_poly
			(pts
				(xy -1.778 1.8796) (xy -1.778 -1.8796) (xy 1.778 -1.8796) (xy 1.778 1.8796)
			)
			(stroke
				(width 0)
				(type default)
			)
			(fill no)
			(layer "F.CrtYd")
		)
		(fp_poly
			(pts
				(xy -1.778 1.8796) (xy -1.778 -1.8796) (xy 1.778 -1.8796) (xy 1.778 1.8796)
			)
			(stroke
				(width 0)
				(type default)
			)
			(fill no)
			(layer "F.Fab")
		)
		(pad "D" smd custom
			(at 0 -0.9525 180)
			(size 0.1905 0.1905)
			(layers "F.Cu" "F.Mask" "F.Paste")
			(net "HDD5_LED_G")
			(options
				(clearance outline)
				(anchor circle)
			)
			(primitives
				(gr_poly
					(pts
						(arc
							(start -0.1778 0.5715)
							(mid -0.321484 0.511984)
							(end -0.381 0.3683)
						)
						(arc
							(start -0.381 -0.3683)
							(mid -0.321484 -0.511984)
							(end -0.1778 -0.5715)
						)
						(arc
							(start 0.1778 -0.5715)
							(mid 0.321484 -0.511984)
							(end 0.381 -0.3683)
						)
						(arc
							(start 0.381 0.3683)
							(mid 0.321484 0.511984)
							(end 0.1778 0.5715)
						)
					)
					(width 0)
					(fill yes)
				)
			)
		)
		(pad "G" smd custom
			(at -0.98425 0.9525 180)
			(size 0.1905 0.1905)
			(layers "F.Cu" "F.Mask" "F.Paste")
			(net "HDD5_LED_B")
			(options
				(clearance outline)
				(anchor circle)
			)
			(primitives
				(gr_poly
					(pts
						(arc
							(start -0.1778 0.5715)
							(mid -0.321484 0.511984)
							(end -0.381 0.3683)
						)
						(arc
							(start -0.381 -0.3683)
							(mid -0.321484 -0.511984)
							(end -0.1778 -0.5715)
						)
						(arc
							(start 0.1778 -0.5715)
							(mid 0.321484 -0.511984)
							(end 0.381 -0.3683)
						)
						(arc
							(start 0.381 0.3683)
							(mid 0.321484 0.511984)
							(end 0.1778 0.5715)
						)
					)
					(width 0)
					(fill yes)
				)
			)
		)
		(pad "S" smd custom
			(at 0.98425 0.9525 180)
			(size 0.1905 0.1905)
			(layers "F.Cu" "F.Mask" "F.Paste")
			(net "GND")
			(options
				(clearance outline)
				(anchor circle)
			)
			(primitives
				(gr_poly
					(pts
						(arc
							(start -0.1778 0.5715)
							(mid -0.321484 0.511984)
							(end -0.381 0.3683)
						)
						(arc
							(start -0.381 -0.3683)
							(mid -0.321484 -0.511984)
							(end -0.1778 -0.5715)
						)
						(arc
							(start 0.1778 -0.5715)
							(mid 0.321484 -0.511984)
							(end 0.381 -0.3683)
						)
						(arc
							(start 0.381 0.3683)
							(mid 0.321484 0.511984)
							(end 0.1778 0.5715)
						)
					)
					(width 0)
					(fill yes)
				)
			)
		)
	)
	(footprint ""
		(layer "F.Cu")
		(at 38.099746 -131.473702 -90)
		(property "Reference" "R291"
			(at 0 0 270)
			(layer "F.SilkS")
			(hide yes)
			(effects
				(font
					(size 1.27 1.27)
				)
			)
		)
		(property "Value" "4K7R2J-2-GP"
			(at 0.064008 -3.993896 270)
			(unlocked yes)
			(layer "F.Fab")
			(hide yes)
			(effects
				(font
					(size 1.016 1.016)
					(thickness 0.1524)
				)
			)
		)
		(property "Device Type" "R402H16"
			(at 0.064008 -5.517896 270)
			(unlocked yes)
			(layer "F.Fab")
			(hide yes)
			(effects
				(font
					(size 1.016 1.016)
					(thickness 0.1524)
				)
			)
		)
		(duplicate_pad_numbers_are_jumpers no)
		(fp_line
			(start -0.508 -0.9398)
			(end -0.508 0.9398)
			(stroke
				(width 0.1524)
				(type default)
			)
			(layer "F.SilkS")
		)
		(fp_line
			(start 0.508 -0.9398)
			(end -0.508 -0.9398)
			(stroke
				(width 0.1524)
				(type default)
			)
			(layer "F.SilkS")
		)
		(fp_rect
			(start -0.508 0.9398)
			(end 0.508 -0.9398)
			(stroke
				(width 0)
				(type default)
			)
			(fill no)
			(layer "F.CrtYd")
		)
		(fp_rect
			(start -0.508 0.9398)
			(end 0.508 -0.9398)
			(stroke
				(width 0)
				(type default)
			)
			(fill no)
			(layer "F.Fab")
		)
		(pad "1" smd custom
			(at 0 -0.4445 270)
			(size 0.1397 0.1397)
			(layers "F.Cu" "F.Mask" "F.Paste")
			(net "P3V3")
			(options
				(clearance outline)
				(anchor circle)
			)
			(primitives
				(gr_poly
					(pts
						(arc
							(start -0.1778 -0.2794)
							(mid -0.249642 -0.249642)
							(end -0.2794 -0.1778)
						)
						(arc
							(start -0.2794 0.1778)
							(mid -0.249642 0.249642)
							(end -0.1778 0.2794)
						)
						(arc
							(start 0.1778 0.2794)
							(mid 0.249642 0.249642)
							(end 0.2794 0.1778)
						)
						(arc
							(start 0.2794 -0.1778)
							(mid 0.249642 -0.249642)
							(end 0.1778 -0.2794)
						)
					)
					(width 0)
					(fill yes)
				)
			)
		)
		(pad "2" smd custom
			(at 0 0.4445 270)
			(size 0.1397 0.1397)
			(layers "F.Cu" "F.Mask" "F.Paste")
			(net "HDD_PRSNT_NET13")
			(options
				(clearance outline)
				(anchor circle)
			)
			(primitives
				(gr_poly
					(pts
						(arc
							(start -0.1778 -0.2794)
							(mid -0.249642 -0.249642)
							(end -0.2794 -0.1778)
						)
						(arc
							(start -0.2794 0.1778)
							(mid -0.249642 0.249642)
							(end -0.1778 0.2794)
						)
						(arc
							(start 0.1778 0.2794)
							(mid 0.249642 0.249642)
							(end 0.2794 0.1778)
						)
						(arc
							(start 0.2794 -0.1778)
							(mid 0.249642 -0.249642)
							(end 0.1778 -0.2794)
						)
					)
					(width 0)
					(fill yes)
				)
			)
		)
	)
	(footprint ""
		(layer "F.Cu")
		(at 71.246746 -87.2617)
		(property "Reference" "R456"
			(at 0 0 0)
			(layer "F.SilkS")
			(hide yes)
			(effects
				(font
					(size 1.27 1.27)
				)
			)
		)
		(property "Value" "4K7R2J-2-GP"
			(at 0.064008 -3.993896 0)
			(unlocked yes)
			(layer "F.Fab")
			(hide yes)
			(effects
				(font
					(size 1.016 1.016)
					(thickness 0.1524)
				)
			)
		)
		(property "Device Type" "R402H16"
			(at 0.064008 -5.517896 0)
			(unlocked yes)
			(layer "F.Fab")
			(hide yes)
			(effects
				(font
					(size 1.016 1.016)
					(thickness 0.1524)
				)
			)
		)
		(duplicate_pad_numbers_are_jumpers no)
		(fp_line
			(start -0.508 -0.9398)
			(end -0.508 0.9398)
			(stroke
				(width 0.1524)
				(type default)
			)
			(layer "F.SilkS")
		)
		(fp_line
			(start 0.508 -0.9398)
			(end -0.508 -0.9398)
			(stroke
				(width 0.1524)
				(type default)
			)
			(layer "F.SilkS")
		)
		(fp_rect
			(start -0.508 0.9398)
			(end 0.508 -0.9398)
			(stroke
				(width 0)
				(type default)
			)
			(fill no)
			(layer "F.CrtYd")
		)
		(fp_rect
			(start -0.508 0.9398)
			(end 0.508 -0.9398)
			(stroke
				(width 0)
				(type default)
			)
			(fill no)
			(layer "F.Fab")
		)
		(pad "1" smd custom
			(at 0 -0.4445)
			(size 0.1397 0.1397)
			(layers "F.Cu" "F.Mask" "F.Paste")
			(net "P3V3")
			(options
				(clearance outline)
				(anchor circle)
			)
			(primitives
				(gr_poly
					(pts
						(arc
							(start -0.1778 -0.2794)
							(mid -0.249642 -0.249642)
							(end -0.2794 -0.1778)
						)
						(arc
							(start -0.2794 0.1778)
							(mid -0.249642 0.249642)
							(end -0.1778 0.2794)
						)
						(arc
							(start 0.1778 0.2794)
							(mid 0.249642 0.249642)
							(end 0.2794 0.1778)
						)
						(arc
							(start 0.2794 -0.1778)
							(mid 0.249642 -0.249642)
							(end 0.1778 -0.2794)
						)
					)
					(width 0)
					(fill yes)
				)
			)
		)
		(pad "2" smd custom
			(at 0 0.4445)
			(size 0.1397 0.1397)
			(layers "F.Cu" "F.Mask" "F.Paste")
			(net "SAS2X28_A_HDD9_FLT")
			(options
				(clearance outline)
				(anchor circle)
			)
			(primitives
				(gr_poly
					(pts
						(arc
							(start -0.1778 -0.2794)
							(mid -0.249642 -0.249642)
							(end -0.2794 -0.1778)
						)
						(arc
							(start -0.2794 0.1778)
							(mid -0.249642 0.249642)
							(end -0.1778 0.2794)
						)
						(arc
							(start 0.1778 0.2794)
							(mid 0.249642 0.249642)
							(end 0.2794 0.1778)
						)
						(arc
							(start 0.2794 -0.1778)
							(mid 0.249642 -0.249642)
							(end 0.1778 -0.2794)
						)
					)
					(width 0)
					(fill yes)
				)
			)
		)
	)
)
